# T6G (Grand Teton) — schematic netlist excerpt (pin names and nets, part order shuffled) for the footprints in the layout excerpt that follows; sources: Cadence DE-HDL packaged netlist, KiCad conversion of 04192023_DAF0TMB3IC0_F0TG_MB_C_brd_V02_OCP.brd

U8000  NC7SB3157P6X  IC  pkg SC70-6XA  page 153
  B1  = ESPI_CPU0_ALERT_R1_N
  GND  = GND
  B0  = ESPI_CPU0_ALERT_PLD_N
  A  = ESPI_CPU0_ALERT_P0_N
  VCC  = P1V8_AUX
  S  = FM_ESPI_CPU0_ALERT_R_SEL

PC187_3  Q_CAP  22UF 16V 20% X6S  pkg C0805  page 206 : A = SW_P12V_AUX_PVDDIO_P0_FLT ; B = GND

(kicad_pcb
	(version 20260206)
	(generator "pcbnew")
	(generator_version "10.0")
	(general
		(thickness 1.6)
		(legacy_teardrops no)
	)
	(paper "A4")
	(title_block
		(title "04192023_DAF0TMB3IC0_F0TG_MB_C_brd_V02_OCP.brd")
		(comment 1 "Grand Teton / footprints 7113-7114 of 8354")
	)
	(layers
		(0 "F.Cu" signal "TOP")
		(4 "In1.Cu" signal "GND")
		(6 "In2.Cu" signal "IN1")
		(8 "In3.Cu" signal "GND1")
		(10 "In4.Cu" signal "IN2")
		(12 "In5.Cu" signal "GND2")
		(14 "In6.Cu" signal "IN3")
		(16 "In7.Cu" signal "GND3")
		(18 "In8.Cu" signal "VCC")
		(20 "In9.Cu" signal "VCC1")
		(22 "In10.Cu" signal "GND4")
		(24 "In11.Cu" signal "IN4")
		(26 "In12.Cu" signal "GND5")
		(28 "In13.Cu" signal "IN5")
		(30 "In14.Cu" signal "GND6")
		(32 "In15.Cu" signal "IN6")
		(34 "In16.Cu" signal "GND7")
		(2 "B.Cu" signal "BOTTOM")
		(9 "F.Adhes" user "F.Adhesive")
		(11 "B.Adhes" user "B.Adhesive")
		(13 "F.Paste" user "Package Geometry/Pastemask Top")
		(15 "B.Paste" user "Package Geometry/Pastemask Bottom")
		(5 "F.SilkS" user "Ref Des/Silkscreen Top")
		(7 "B.SilkS" user "Ref Des/Silkscreen Bottom")
		(1 "F.Mask" user "Board Geometry/Soldermask Top")
		(3 "B.Mask" user "Board Geometry/Soldermask Bottom")
		(17 "Dwgs.User" user "User.Drawings")
		(19 "Cmts.User" user "User.Comments")
		(21 "Eco1.User" user "User.Eco1")
		(23 "Eco2.User" user "User.Eco2")
		(25 "Edge.Cuts" user "Board Geometry/Outline")
		(27 "Margin" user)
		(31 "F.CrtYd" user "Package Geometry/Place Bound Top")
		(29 "B.CrtYd" user "Package Geometry/Place Bound Bottom")
		(35 "F.Fab" user "Ref Des/Assembly Top")
		(33 "B.Fab" user "Ref Des/Assembly Bottom")
	)
	(footprint ""
		(layer "B.Cu")
		(at 184.785 -144.399 180)
		(property "Reference" "U8000"
			(at 0.625602 -2.39903 0)
			(unlocked yes)
			(layer "B.SilkS")
			(effects
				(font
					(size 0.7874 0.5842)
					(thickness 0.1524)
				)
				(justify mirror)
			)
		)
		(property "Value" ""
			(at 0 0 0)
			(layer "B.Fab")
			(effects
				(font
					(size 1.27 1.27)
				)
				(justify mirror)
			)
		)
		(duplicate_pad_numbers_are_jumpers no)
		(fp_line
			(start 1.34493 1.100074)
			(end 1.34493 -1.100074)
			(stroke
				(width 0.1524)
				(type default)
			)
			(layer "B.SilkS")
		)
		(fp_line
			(start 1.34493 -1.100074)
			(end 0.420878 -1.100074)
			(stroke
				(width 0.1524)
				(type default)
			)
			(layer "B.SilkS")
		)
		(fp_line
			(start 0.420878 -1.100074)
			(end -0.039878 -0.592074)
			(stroke
				(width 0.1524)
				(type default)
			)
			(layer "B.SilkS")
		)
		(fp_line
			(start -0.039878 -0.592074)
			(end -0.420878 -1.100074)
			(stroke
				(width 0.1524)
				(type default)
			)
			(layer "B.SilkS")
		)
		(fp_line
			(start -0.420878 -1.100074)
			(end -1.35509 -1.100074)
			(stroke
				(width 0.1524)
				(type default)
			)
			(layer "B.SilkS")
		)
		(fp_line
			(start -1.35509 1.100074)
			(end 1.34493 1.100074)
			(stroke
				(width 0.1524)
				(type default)
			)
			(layer "B.SilkS")
		)
		(fp_line
			(start -1.35509 -1.100074)
			(end -1.35509 1.100074)
			(stroke
				(width 0.1524)
				(type default)
			)
			(layer "B.SilkS")
		)
		(fp_poly
			(pts
				(xy 1.867662 -1.667764) (xy 2.324608 -1.058164) (xy 1.486408 -0.906018)
			)
			(stroke
				(width 0)
				(type default)
			)
			(fill yes)
			(layer "B.SilkS")
		)
		(fp_line
			(start 0.674878 1.100074)
			(end 0.674878 -1.100074)
			(stroke
				(width 0.1)
				(type default)
			)
			(layer "B.Fab")
		)
		(fp_line
			(start 0.674878 -1.100074)
			(end -0.674878 -1.100074)
			(stroke
				(width 0.1)
				(type default)
			)
			(layer "B.Fab")
		)
		(fp_line
			(start -0.674878 1.100074)
			(end 0.674878 1.100074)
			(stroke
				(width 0.1)
				(type default)
			)
			(layer "B.Fab")
		)
		(fp_line
			(start -0.674878 -1.100074)
			(end -0.674878 1.100074)
			(stroke
				(width 0.1)
				(type default)
			)
			(layer "B.Fab")
		)
		(fp_poly
			(pts
				(xy 2.286 -1.030986) (xy 2.286 -0.268986) (xy 1.524 -0.649986)
			)
			(stroke
				(width 0)
				(type default)
			)
			(fill yes)
			(layer "B.Fab")
		)
		(pad "1" smd rect
			(at 0.94996 -0.649986 90)
			(size 0.4064 0.508)
			(layers "B.Cu" "B.Mask" "B.Paste")
			(net "ESPI_CPU0_ALERT_R1_N")
		)
		(pad "2" smd rect
			(at 0.94996 0 90)
			(size 0.4064 0.508)
			(layers "B.Cu" "B.Mask" "B.Paste")
			(net "GND")
		)
		(pad "3" smd rect
			(at 0.94996 0.649986 90)
			(size 0.4064 0.508)
			(layers "B.Cu" "B.Mask" "B.Paste")
			(net "ESPI_CPU0_ALERT_PLD_N")
		)
		(pad "4" smd rect
			(at -0.94996 0.649986 90)
			(size 0.4064 0.508)
			(layers "B.Cu" "B.Mask" "B.Paste")
			(net "ESPI_CPU0_ALERT_P0_N")
		)
		(pad "5" smd rect
			(at -0.94996 0 90)
			(size 0.4064 0.508)
			(layers "B.Cu" "B.Mask" "B.Paste")
			(net "P1V8_AUX")
		)
		(pad "6" smd rect
			(at -0.94996 -0.649986 90)
			(size 0.4064 0.508)
			(layers "B.Cu" "B.Mask" "B.Paste")
			(net "FM_ESPI_CPU0_ALERT_R_SEL")
		)
	)
	(footprint ""
		(layer "B.Cu")
		(at 284.82417 -350.65589 -90)
		(property "Reference" "PC187_3"
			(at 0 0 90)
			(layer "B.SilkS")
			(hide yes)
			(effects
				(font
					(size 1.27 1.27)
				)
				(justify mirror)
			)
		)
		(property "Value" ""
			(at 0 0 90)
			(layer "B.Fab")
			(effects
				(font
					(size 1.27 1.27)
				)
				(justify mirror)
			)
		)
		(duplicate_pad_numbers_are_jumpers no)
		(fp_line
			(start -1.524 0.762)
			(end 1.524 0.762)
			(stroke
				(width 0.1524)
				(type default)
			)
			(layer "B.SilkS")
		)
		(fp_line
			(start 1.524 0.762)
			(end 1.524 -0.762)
			(stroke
				(width 0.1524)
				(type default)
			)
			(layer "B.SilkS")
		)
		(fp_line
			(start -1.524 -0.762)
			(end -1.524 0.762)
			(stroke
				(width 0.1524)
				(type default)
			)
			(layer "B.SilkS")
		)
		(fp_line
			(start 1.524 -0.762)
			(end -1.524 -0.762)
			(stroke
				(width 0.1524)
				(type default)
			)
			(layer "B.SilkS")
		)
		(fp_line
			(start -1.1049 0.724916)
			(end -1.1049 -0.724916)
			(stroke
				(width 0.1)
				(type default)
			)
			(layer "B.Fab")
		)
		(fp_line
			(start 1.1049 0.724916)
			(end -1.1049 0.724916)
			(stroke
				(width 0.1)
				(type default)
			)
			(layer "B.Fab")
		)
		(fp_line
			(start -1.1049 -0.724916)
			(end 1.1049 -0.724916)
			(stroke
				(width 0.1)
				(type default)
			)
			(layer "B.Fab")
		)
		(fp_line
			(start 1.1049 -0.724916)
			(end 1.1049 0.724916)
			(stroke
				(width 0.1)
				(type default)
			)
			(layer "B.Fab")
		)
		(pad "1" smd rect
			(at 0.889 0 270)
			(size 1.016 1.27)
			(layers "B.Cu" "B.Mask" "B.Paste")
			(net "SW_P12V_AUX_PVDDIO_P0_FLT")
		)
		(pad "2" smd rect
			(at -0.889 0 270)
			(size 1.016 1.27)
			(layers "B.Cu" "B.Mask" "B.Paste")
			(net "GND")
		)
	)
)
